# TIMECARD (Time Appliance Project (Time Card)) — schematic netlist excerpt (pin names and nets, part order shuffled) for the footprints in the layout excerpt that follows; sources: Cadence DE-HDL packaged netlist, KiCad conversion of R4006-B0001-02_R01.brd

DS11  OPTICAL  pkg SMC_DS_063X031_V4  page 26 : A = UNNAMED_14_OPTICAL_I139_A ; C = FPGA_USR_LED0
C75  CAPACITOR  0.01UF 25V 10%  pkg SMC_0201R  page 32 : \1\ = SG ; \2\ = XP5R0V_PG

(kicad_pcb
	(version 20260206)
	(generator "pcbnew")
	(generator_version "10.0")
	(general
		(thickness 1.6)
		(legacy_teardrops no)
	)
	(paper "A4")
	(title_block
		(title "timecard-production-celestica-r4006 — R4006-B0001-02_R01.brd")
		(comment 1 "Time Appliance Project (Time Card) / footprints 272-273 of 1113")
	)
	(layers
		(0 "F.Cu" signal "TOP")
		(4 "In1.Cu" signal "L02_GND1")
		(6 "In2.Cu" signal "L03_SIG1")
		(8 "In3.Cu" signal "L04_GND2")
		(10 "In4.Cu" signal "L05_VCC1")
		(12 "In5.Cu" signal "L06_VCC2")
		(14 "In6.Cu" signal "L07_GND3")
		(16 "In7.Cu" signal "L08_SIG2")
		(18 "In8.Cu" signal "L09_GND4")
		(2 "B.Cu" signal "BOTTOM")
		(9 "F.Adhes" user "F.Adhesive")
		(11 "B.Adhes" user "B.Adhesive")
		(13 "F.Paste" user "Package Geometry/Pastemask Top")
		(15 "B.Paste" user "Package Geometry/Pastemask Bottom")
		(5 "F.SilkS" user "Ref Des/Silkscreen Top")
		(7 "B.SilkS" user "Ref Des/Silkscreen Bottom")
		(1 "F.Mask" user "Board Geometry/Soldermask Top")
		(3 "B.Mask" user "Board Geometry/Soldermask Bottom")
		(17 "Dwgs.User" user "User.Drawings")
		(19 "Cmts.User" user "User.Comments")
		(21 "Eco1.User" user "User.Eco1")
		(23 "Eco2.User" user "User.Eco2")
		(25 "Edge.Cuts" user "Board Geometry/Outline")
		(27 "Margin" user)
		(31 "F.CrtYd" user "Package Geometry/Place Bound Top")
		(29 "B.CrtYd" user "Package Geometry/Place Bound Bottom")
		(35 "F.Fab" user "Ref Des/Assembly Top")
		(33 "B.Fab" user "Ref Des/Assembly Bottom")
	)
	(footprint ""
		(layer "F.Cu")
		(at 37.1094 -99.0854)
		(property "Reference" "C75"
			(at 1.6256 6.28777 0)
			(unlocked yes)
			(layer "F.SilkS")
			(effects
				(font
					(size 0.7874 0.5842)
					(thickness 0.1524)
				)
			)
		)
		(property "Value" "VAL*"
			(at 0.193548 2.13614 0)
			(unlocked yes)
			(layer "F.Fab")
			(hide yes)
			(effects
				(font
					(size 0.7874 0.5842)
					(thickness 0.1524)
				)
			)
		)
		(property "Tolerance" "TOL*"
			(at 0.216154 3.1496 0)
			(unlocked yes)
			(layer "Cmts.User")
			(hide yes)
			(effects
				(font
					(size 0.7874 0.5842)
					(thickness 0.1524)
				)
			)
		)
		(property "Device Type" "CAPACITOR-G104-0B103-EK,0.01UFA"
			(at 0.184404 1.180592 0)
			(unlocked yes)
			(layer "F.Fab")
			(hide yes)
			(effects
				(font
					(size 0.7874 0.5842)
					(thickness 0.1524)
				)
			)
		)
		(property "User Part Number" "PARTNUM*"
			(at 0.216154 4.185666 0)
			(unlocked yes)
			(layer "Cmts.User")
			(hide yes)
			(effects
				(font
					(size 0.7874 0.5842)
					(thickness 0.1524)
				)
			)
		)
		(duplicate_pad_numbers_are_jumpers no)
		(fp_line
			(start -0.671322 -0.4445)
			(end 0.671322 -0.4445)
			(stroke
				(width 0.1)
				(type default)
			)
			(layer "F.SilkS")
		)
		(fp_line
			(start -0.671322 0.4445)
			(end -0.671322 -0.4445)
			(stroke
				(width 0.1)
				(type default)
			)
			(layer "F.SilkS")
		)
		(fp_line
			(start 0.671322 -0.4445)
			(end 0.671322 0.4445)
			(stroke
				(width 0.1)
				(type default)
			)
			(layer "F.SilkS")
		)
		(fp_line
			(start 0.671322 0.4445)
			(end -0.671322 0.4445)
			(stroke
				(width 0.1)
				(type default)
			)
			(layer "F.SilkS")
		)
		(fp_rect
			(start 0.671322 -0.4445)
			(end -0.671322 0.4445)
			(stroke
				(width 0)
				(type default)
			)
			(fill no)
			(layer "F.CrtYd")
		)
		(fp_line
			(start -0.31496 -0.1651)
			(end -0.31496 0.1651)
			(stroke
				(width 0.1)
				(type default)
			)
			(layer "F.Fab")
		)
		(fp_line
			(start -0.31496 0.1651)
			(end 0.31496 0.1651)
			(stroke
				(width 0.1)
				(type default)
			)
			(layer "F.Fab")
		)
		(fp_line
			(start 0.31496 -0.1651)
			(end -0.31496 -0.1651)
			(stroke
				(width 0.1)
				(type default)
			)
			(layer "F.Fab")
		)
		(fp_line
			(start 0.31496 0.1651)
			(end 0.31496 -0.1651)
			(stroke
				(width 0.1)
				(type default)
			)
			(layer "F.Fab")
		)
		(pad "1" smd rect
			(at -0.264922 0)
			(size 0.3048 0.381)
			(layers "F.Cu" "F.Mask" "F.Paste")
			(net "SG")
		)
		(pad "2" smd rect
			(at 0.264922 0)
			(size 0.3048 0.381)
			(layers "F.Cu" "F.Mask" "F.Paste")
			(net "XP5R0V_PG")
		)
		(zone
			(layer "F.Cu")
			(hatch none 0.5)
			(connect_pads
				(clearance 0)
			)
			(min_thickness 0.25)
			(keepout
				(tracks allowed)
				(vias not_allowed)
				(pads allowed)
				(copperpour not_allowed)
				(footprints allowed)
			)
			(placement
				(enabled no)
				(sheetname "")
			)
			(fill
				(thermal_gap 0.5)
				(thermal_bridge_width 0.5)
				(island_removal_mode 0)
			)
			(polygon
				(pts
					(xy 37.221922 -99.2759) (xy 36.996878 -99.2759) (xy 36.996878 -98.8949) (xy 37.221922 -98.8949)
				)
			)
		)
	)
	(footprint ""
		(layer "F.Cu")
		(at 156.04998 -107.849924 -90)
		(property "Reference" "DS11"
			(at -0.100076 -2.23139 90)
			(unlocked yes)
			(layer "F.SilkS")
			(effects
				(font
					(size 0.7874 0.5842)
					(thickness 0.1524)
				)
			)
		)
		(property "Value" ""
			(at 0 0 270)
			(layer "F.Fab")
			(effects
				(font
					(size 1.27 1.27)
				)
			)
		)
		(property "Device Type" "OPTICAL-G170-10143-01"
			(at 0.1778 1.483081 270)
			(unlocked yes)
			(layer "F.Fab")
			(hide yes)
			(effects
				(font
					(size 0.786892 0.583946)
					(thickness 0.000001)
				)
			)
		)
		(property "User Part Number" "PARTNUM*"
			(at 0.1778 2.422881 270)
			(unlocked yes)
			(layer "Cmts.User")
			(hide yes)
			(effects
				(font
					(size 0.786892 0.583946)
					(thickness 0.000001)
				)
			)
		)
		(duplicate_pad_numbers_are_jumpers no)
		(fp_line
			(start -1.3208 1.0922)
			(end -2.5908 1.0922)
			(stroke
				(width 0.1)
				(type default)
			)
			(layer "F.SilkS")
		)
		(fp_line
			(start -1.397508 0.704088)
			(end -1.397508 -0.704088)
			(stroke
				(width 0.1)
				(type default)
			)
			(layer "F.SilkS")
		)
		(fp_line
			(start 1.397508 0.704088)
			(end -1.397508 0.704088)
			(stroke
				(width 0.1)
				(type default)
			)
			(layer "F.SilkS")
		)
		(fp_line
			(start -1.9558 0.4572)
			(end -1.9558 1.7272)
			(stroke
				(width 0.1)
				(type default)
			)
			(layer "F.SilkS")
		)
		(fp_line
			(start -1.397508 -0.704088)
			(end 1.397508 -0.704088)
			(stroke
				(width 0.1)
				(type default)
			)
			(layer "F.SilkS")
		)
		(fp_line
			(start 1.397508 -0.704088)
			(end 1.397508 0.704088)
			(stroke
				(width 0.1)
				(type default)
			)
			(layer "F.SilkS")
		)
		(fp_rect
			(start 1.905508 0.704088)
			(end 1.397508 -0.704088)
			(stroke
				(width 0)
				(type default)
			)
			(fill yes)
			(layer "F.SilkS")
		)
		(fp_rect
			(start 1.905508 0.958088)
			(end -1.651508 -0.958088)
			(stroke
				(width 0)
				(type default)
			)
			(fill no)
			(layer "F.CrtYd")
		)
		(fp_line
			(start -1.1938 1.2192)
			(end -2.4638 1.2192)
			(stroke
				(width 0.1)
				(type default)
			)
			(layer "F.Fab")
		)
		(fp_line
			(start -1.8288 0.5842)
			(end -1.8288 1.8542)
			(stroke
				(width 0.1)
				(type default)
			)
			(layer "F.Fab")
		)
		(fp_line
			(start -0.850138 0.450088)
			(end 0.850138 0.450088)
			(stroke
				(width 0.1)
				(type default)
			)
			(layer "F.Fab")
		)
		(fp_line
			(start 0.850138 0.450088)
			(end 0.850138 -0.450088)
			(stroke
				(width 0.1)
				(type default)
			)
			(layer "F.Fab")
		)
		(fp_line
			(start -0.850138 -0.450088)
			(end -0.850138 0.450088)
			(stroke
				(width 0.1)
				(type default)
			)
			(layer "F.Fab")
		)
		(fp_line
			(start 0.850138 -0.450088)
			(end -0.850138 -0.450088)
			(stroke
				(width 0.1)
				(type default)
			)
			(layer "F.Fab")
		)
		(fp_rect
			(start 0.850138 0.450088)
			(end 0.342138 -0.450088)
			(stroke
				(width 0)
				(type default)
			)
			(fill yes)
			(layer "F.Fab")
		)
		(fp_text user "A"
			(at -1.719326 -1.30302 0)
			(unlocked yes)
			(layer "F.SilkS")
			(effects
				(font
					(size 0.635 0.4064)
					(thickness 0.1524)
				)
			)
		)
		(fp_text user "C"
			(at 1.455674 -1.30302 0)
			(unlocked yes)
			(layer "F.SilkS")
			(effects
				(font
					(size 0.635 0.4064)
					(thickness 0.1524)
				)
			)
		)
		(fp_text user "A"
			(at -2.219706 -0.16002 0)
			(unlocked yes)
			(layer "F.Fab")
			(effects
				(font
					(size 0.7874 0.5842)
					(thickness 0.1524)
				)
			)
		)
		(fp_text user "C"
			(at 1.209294 -1.17602 0)
			(unlocked yes)
			(layer "F.Fab")
			(effects
				(font
					(size 0.7874 0.5842)
					(thickness 0.1524)
				)
			)
		)
		(pad "A" smd rect
			(at -0.749808 0 270)
			(size 0.7874 0.7874)
			(layers "F.Cu" "F.Mask" "F.Paste")
			(net "UNNAMED_14_OPTICAL_I139_A")
		)
		(pad "C" smd rect
			(at 0.749808 0 270)
			(size 0.7874 0.7874)
			(layers "F.Cu" "F.Mask" "F.Paste")
			(net "FPGA_USR_LED0")
		)
	)
)
